# S9S_MB_2U (Grand Teton) — schematic netlist excerpt (pin names and nets, part order shuffled) for the footprints in the layout excerpt that follows; sources: Cadence DE-HDL packaged netlist, KiCad conversion of 03242023_DA0F0TMBIJ0_F0T_Motherboard_J_brd_V01_OCP.brd

J74  PICOPROBE_BXA  DELTA-L 4.0 EMPTY  pkg TRIANG_LAUNCH_3PXB  page 308
  \1_p\  = DELTA_L_85_5INCH_IN4_DN
  \2_n\  = DELTA_L_85_5INCH_IN4_DP
  \3_g\  = DELTA_L_GND_1

(kicad_pcb
	(version 20260206)
	(generator "pcbnew")
	(generator_version "10.0")
	(general
		(thickness 1.6)
		(legacy_teardrops no)
	)
	(paper "A4")
	(title_block
		(title "03242023_DA0F0TMBIJ0_F0T_Motherboard_J_brd_V01_OCP.brd")
		(comment 1 "Grand Teton / footprints 5045-5045 of 6105")
	)
	(layers
		(0 "F.Cu" signal "TOP")
		(4 "In1.Cu" signal "GND")
		(6 "In2.Cu" signal "IN1")
		(8 "In3.Cu" signal "GND1")
		(10 "In4.Cu" signal "IN2")
		(12 "In5.Cu" signal "GND2")
		(14 "In6.Cu" signal "IN3")
		(16 "In7.Cu" signal "GND3")
		(18 "In8.Cu" signal "VCC")
		(20 "In9.Cu" signal "VCC1")
		(22 "In10.Cu" signal "GND4")
		(24 "In11.Cu" signal "IN4")
		(26 "In12.Cu" signal "GND5")
		(28 "In13.Cu" signal "IN5")
		(30 "In14.Cu" signal "GND6")
		(32 "In15.Cu" signal "IN6")
		(34 "In16.Cu" signal "GND7")
		(2 "B.Cu" signal "BOTTOM")
		(9 "F.Adhes" user "F.Adhesive")
		(11 "B.Adhes" user "B.Adhesive")
		(13 "F.Paste" user "Package Geometry/Pastemask Top")
		(15 "B.Paste" user "Package Geometry/Pastemask Bottom")
		(5 "F.SilkS" user "Ref Des/Silkscreen Top")
		(7 "B.SilkS" user "Ref Des/Silkscreen Bottom")
		(1 "F.Mask" user "Board Geometry/Soldermask Top")
		(3 "B.Mask" user "Board Geometry/Soldermask Bottom")
		(17 "Dwgs.User" user "User.Drawings")
		(19 "Cmts.User" user "User.Comments")
		(21 "Eco1.User" user "User.Eco1")
		(23 "Eco2.User" user "User.Eco2")
		(25 "Edge.Cuts" user "Board Geometry/Outline")
		(27 "Margin" user)
		(31 "F.CrtYd" user "Package Geometry/Place Bound Top")
		(29 "B.CrtYd" user "Package Geometry/Place Bound Bottom")
		(35 "F.Fab" user "Ref Des/Assembly Top")
		(33 "B.Fab" user "Ref Des/Assembly Bottom")
	)
	(footprint ""
		(layer "B.Cu")
		(at 211.85378 -2.159 180)
		(property "Reference" "J74"
			(at 4.23545 -1.143 270)
			(unlocked yes)
			(layer "B.SilkS")
			(effects
				(font
					(size 0.7874 0.5842)
					(thickness 0.1524)
				)
				(justify left mirror)
			)
		)
		(property "Value" ""
			(at 0 0 0)
			(layer "B.Fab")
			(effects
				(font
					(size 1.27 1.27)
				)
				(justify mirror)
			)
		)
		(duplicate_pad_numbers_are_jumpers no)
		(fp_line
			(start 1.2192 2.1082)
			(end 1.2192 -2.1082)
			(stroke
				(width 0.1524)
				(type default)
			)
			(layer "B.SilkS")
		)
		(fp_line
			(start 1.2192 -2.1082)
			(end -1.2192 -2.1082)
			(stroke
				(width 0.1524)
				(type default)
			)
			(layer "B.SilkS")
		)
		(fp_line
			(start -1.2192 2.1082)
			(end 1.2192 2.1082)
			(stroke
				(width 0.1524)
				(type default)
			)
			(layer "B.SilkS")
		)
		(fp_line
			(start -1.2192 -2.1082)
			(end -1.2192 2.1082)
			(stroke
				(width 0.1524)
				(type default)
			)
			(layer "B.SilkS")
		)
		(pad "" np_thru_hole circle
			(at -3.4671 -1.27 90)
			(size 1.0414 1.0414)
			(drill 1.0414)
			(layers "*.Cu" "*.Mask")
			(clearance 0.381)
			(thermal_gap 0.381)
		)
		(pad "" np_thru_hole circle
			(at -3.4671 1.27 90)
			(size 1.0414 1.0414)
			(drill 1.0414)
			(layers "*.Cu" "*.Mask")
			(clearance 0.381)
			(thermal_gap 0.381)
		)
		(pad "" np_thru_hole circle
			(at 2.8829 -1.27 90)
			(size 1.0414 1.0414)
			(drill 1.0414)
			(layers "*.Cu" "*.Mask")
			(clearance 0.381)
			(thermal_gap 0.381)
		)
		(pad "" np_thru_hole circle
			(at 2.8829 1.27 90)
			(size 1.0414 1.0414)
			(drill 1.0414)
			(layers "*.Cu" "*.Mask")
			(clearance 0.381)
			(thermal_gap 0.381)
		)
		(pad "1" smd rect
			(at -0.8255 -0.249936 90)
			(size 0.3048 0.508)
			(layers "B.Cu" "B.Mask" "B.Paste")
			(net "DELTA_L_85_5INCH_IN4_DN")
		)
		(pad "2" smd rect
			(at -0.8255 0.249936 90)
			(size 0.3048 0.508)
			(layers "B.Cu" "B.Mask" "B.Paste")
			(net "DELTA_L_85_5INCH_IN4_DP")
		)
		(pad "3" smd circle
			(at 0 0)
			(size 0 0)
			(layers "B.Cu" "B.Mask" "B.Paste")
			(net "DELTA_L_GND_1")
		)
		(zone
			(layers "F.Cu" "B.Cu" "In1.Cu" "In2.Cu" "In3.Cu" "In4.Cu" "In5.Cu" "In6.Cu"
				"In7.Cu" "In8.Cu" "In9.Cu" "In10.Cu" "In11.Cu" "In12.Cu" "In13.Cu" "In14.Cu"
				"In15.Cu" "In16.Cu"
			)
			(hatch none 0.5)
			(connect_pads
				(clearance 0)
			)
			(min_thickness 0.25)
			(keepout
				(tracks not_allowed)
				(vias allowed)
				(pads allowed)
				(copperpour not_allowed)
				(footprints allowed)
			)
			(placement
				(enabled no)
				(sheetname "")
			)
			(fill
				(thermal_gap 0.5)
				(thermal_bridge_width 0.5)
				(island_removal_mode 0)
			)
			(polygon
				(pts
					(arc
						(start 209.89798 -3.429)
						(mid 208.04378 -3.429)
						(end 209.89798 -3.429)
					)
				)
			)
		)
		(zone
			(layers "F.Cu" "B.Cu" "In1.Cu" "In2.Cu" "In3.Cu" "In4.Cu" "In5.Cu" "In6.Cu"
				"In7.Cu" "In8.Cu" "In9.Cu" "In10.Cu" "In11.Cu" "In12.Cu" "In13.Cu" "In14.Cu"
				"In15.Cu" "In16.Cu"
			)
			(hatch none 0.5)
			(connect_pads
				(clearance 0)
			)
			(min_thickness 0.25)
			(keepout
				(tracks not_allowed)
				(vias allowed)
				(pads allowed)
				(copperpour not_allowed)
				(footprints allowed)
			)
			(placement
				(enabled no)
				(sheetname "")
			)
			(fill
				(thermal_gap 0.5)
				(thermal_bridge_width 0.5)
				(island_removal_mode 0)
			)
			(polygon
				(pts
					(arc
						(start 209.89798 -0.889)
						(mid 208.04378 -0.889)
						(end 209.89798 -0.889)
					)
				)
			)
		)
		(zone
			(layers "F.Cu" "B.Cu" "In1.Cu" "In2.Cu" "In3.Cu" "In4.Cu" "In5.Cu" "In6.Cu"
				"In7.Cu" "In8.Cu" "In9.Cu" "In10.Cu" "In11.Cu" "In12.Cu" "In13.Cu" "In14.Cu"
				"In15.Cu" "In16.Cu"
			)
			(hatch none 0.5)
			(connect_pads
				(clearance 0)
			)
			(min_thickness 0.25)
			(keepout
				(tracks not_allowed)
				(vias allowed)
				(pads allowed)
				(copperpour not_allowed)
				(footprints allowed)
			)
			(placement
				(enabled no)
				(sheetname "")
			)
			(fill
				(thermal_gap 0.5)
				(thermal_bridge_width 0.5)
				(island_removal_mode 0)
			)
			(polygon
				(pts
					(arc
						(start 216.24798 -3.429)
						(mid 214.39378 -3.429)
						(end 216.24798 -3.429)
					)
				)
			)
		)
		(zone
			(layers "F.Cu" "B.Cu" "In1.Cu" "In2.Cu" "In3.Cu" "In4.Cu" "In5.Cu" "In6.Cu"
				"In7.Cu" "In8.Cu" "In9.Cu" "In10.Cu" "In11.Cu" "In12.Cu" "In13.Cu" "In14.Cu"
				"In15.Cu" "In16.Cu"
			)
			(hatch none 0.5)
			(connect_pads
				(clearance 0)
			)
			(min_thickness 0.25)
			(keepout
				(tracks not_allowed)
				(vias allowed)
				(pads allowed)
				(copperpour not_allowed)
				(footprints allowed)
			)
			(placement
				(enabled no)
				(sheetname "")
			)
			(fill
				(thermal_gap 0.5)
				(thermal_bridge_width 0.5)
				(island_removal_mode 0)
			)
			(polygon
				(pts
					(arc
						(start 216.24798 -0.889)
						(mid 214.39378 -0.889)
						(end 216.24798 -0.889)
					)
				)
			)
		)
		(zone
			(layer "B.Cu")
			(hatch none 0.5)
			(connect_pads
				(clearance 0)
			)
			(min_thickness 0.25)
			(keepout
				(tracks not_allowed)
				(vias allowed)
				(pads allowed)
				(copperpour not_allowed)
				(footprints allowed)
			)
			(placement
				(enabled no)
				(sheetname "")
			)
			(fill
				(thermal_gap 0.5)
				(thermal_bridge_width 0.5)
				(island_removal_mode 0)
			)
			(polygon
				(pts
					(xy 212.97138 -1.61036) (xy 212.97138 -1.705864) (xy 212.37448 -1.705864) (xy 212.37448 -2.112264)
					(xy 212.97138 -2.112264) (xy 212.97138 -2.205736) (xy 212.37448 -2.205736) (xy 212.37448 -2.612136)
					(xy 212.97138 -2.612136) (xy 212.97138 -2.70764) (xy 212.27288 -2.70764) (xy 212.27288 -1.61036)
				)
			)
		)
	)
)
